;LEADER: 12 
;HEADER: 
;CODE  : ASCII 
;FILE  : 9332_F0TG_MB_C_V02_0417_0820-bd-18-15.drl for backdrilling ... from layer BOTTOM to layer GND6
;DESIGN: 9332_F0TG_MB_C_V02_0417_0820.brd
;MUST-NOT-CUT-LAYER = IN5,  MAX_DRILL_DEPTH = 19.85 MILS,  MFG_STUB_LENGTH = 0.00 MILS
;   BackdrillSize 1. = 14.800000 Tolerance = +0.000000/-0.000000 NON_PLATED MILS Quantity = 776
;   BackdrillSize 2. = 17.000000 Tolerance = +0.000000/-0.000000 NON_PLATED MILS Quantity = 772
;   BackdrillSize 3. = 21.170000 Tolerance = +0.000000/-0.000000 NON_PLATED MILS Quantity = 128
%
G90
X0470845Y1069513
X0470845Y1075891
X0470845Y1063135
X0459743Y1069513
X0459743Y1075891
X0459743Y1063135
X0450491Y1072702
X0450491Y1079080
X0450491Y1066324
X0493050Y1069513
X0493050Y1075891
X0493050Y1063135
X0481948Y1069513
X0481948Y1075891
X0481948Y1063135
X0450491Y1059946
X0474546Y1069513
X0474546Y1075891
X0474546Y1063135
X0463444Y1069513
X0463444Y1075891
X0463444Y1063135
X0454192Y1072702
X0454192Y1079080
X0454192Y1066324
X0496751Y1069513
X0496751Y1075891
X0496751Y1063135
X0485649Y1069513
X0485649Y1075891
X0485649Y1063135
X0454192Y1059946
X0411658Y1075891
X0222800Y1519698
X0411658Y1069513
X0218076Y1519698
X0400555Y1063135
X0213352Y1519698
X0400555Y1075891
X0208627Y1519698
X0400555Y1069513
X0203903Y1519698
X0389453Y1063135
X0199178Y1519698
X0389453Y1075891
X0194454Y1519698
X0389453Y1069513
X0189730Y1519698
X0407957Y1075891
X0221226Y1516970
X0407957Y1069513
X0216501Y1516970
X0396855Y1063135
X0211777Y1516970
X0396855Y1075891
X0207052Y1516970
X0396855Y1069513
X0202328Y1516970
X0385752Y1063135
X0197604Y1516970
X0385752Y1075891
X0192879Y1516970
X0385752Y1069513
X0188155Y1516970
X1446987Y1069512
X1446987Y1075890
X1446987Y1063134
X1435885Y1069512
X1435885Y1075890
X1435885Y1063134
X1426633Y1072701
X1426633Y1079079
X1426633Y1066323
X1469192Y1069512
X1469192Y1075890
X1469192Y1063134
X1458090Y1069512
X1458090Y1075890
X1458090Y1063134
X1426633Y1059945
X1450688Y1069512
X1450688Y1075890
X1450688Y1063134
X1439586Y1069512
X1439586Y1075890
X1439586Y1063134
X1430334Y1072701
X1430334Y1079079
X1430334Y1066323
X1472893Y1069512
X1472893Y1075890
X1472893Y1063134
X1461791Y1069512
X1461791Y1075890
X1461791Y1063134
X1430334Y1059945
X1387800Y1075890
X1230673Y1552698
X1387800Y1069512
X1225949Y1552698
X1376697Y1063134
X1221225Y1552698
X1376697Y1075890
X1216500Y1552698
X1376697Y1069512
X1211776Y1552698
X1365595Y1063134
X1207051Y1552698
X1365595Y1075890
X1202327Y1552698
X1365595Y1069512
X1197603Y1552698
X1384099Y1075890
X1229099Y1549970
X1384099Y1069512
X1224374Y1549970
X1372997Y1063134
X1219650Y1549970
X1372997Y1075890
X1214925Y1549970
X1372997Y1069512
X1210201Y1549970
X1361894Y1063134
X1205477Y1549970
X1361894Y1075890
X1200752Y1549970
X1361894Y1069512
X1196028Y1549970
X0535609Y1053568
X0530058Y1044001
X0535609Y1066324
X0531908Y1149237
X0531908Y1130103
X0531908Y1110970
R02Y-0019134
X0535609Y1142859
X0535609Y1123726
X0535609Y1104592
X0535609Y1085458
X0537460Y1069513
X0530058Y1146048
X0530058Y1126915
X0530058Y1107781
R02Y-0019134
X0537460Y1146048
X0537460Y1126915
X0537460Y1107781
X0537460Y1088647
X0530058Y1101403
X0535609Y1098214
X0531908Y1098214
X0537460Y1095025
X0530058Y1095025
X0535609Y1091836
X0531908Y1085458
X0531908Y1155615
X0537460Y1152426
X0537460Y1082269
X0530058Y1152426
X0535609Y1149237
X0531908Y1142859
X0537460Y1139670
X0530058Y1139670
X0535609Y1136481
X0531908Y1136481
X0537460Y1133293
X0530058Y1133293
X0535609Y1130103
X0530058Y1082269
X0531908Y1123726
X0537460Y1120537
X0530058Y1120537
X0535609Y1117348
X0531908Y1117348
X0537460Y1114159
X0530058Y1114159
X0535609Y1110970
X0531908Y1104592
X0537460Y1101403
X0535609Y1079080
X0537460Y1050379
X0531908Y1047190
X0531908Y1066324
X0537460Y1063135
X0530058Y1063135
X0535609Y1059946
X0531908Y1079080
X0537460Y1075891
X0530058Y1075891
X0535609Y1072702
X0535609Y1040812
X0531908Y1040812
X0530058Y1037623
X0537460Y1037623
X0535609Y1034434
X0531908Y1034434
X0530058Y1031245
X0530058Y1050379
X0528877Y1007183
X0528877Y0975293
X0528877Y0956159
R02Y-0019134
X0528877Y0898758
X0536279Y0968915
R03Y-0019134
X0536279Y0892380
X0530727Y0972104
R03Y-0019134
X0530727Y0895569
X0534428Y0972104
R03Y-0019134
X0534428Y0895569
X0530727Y0908325
X0536279Y0905135
X0528877Y0905135
X0534428Y0901947
X0530727Y0901947
X0536279Y0898758
X0528877Y0892380
X0528877Y0962537
X0534428Y0959348
X0534428Y0889191
X0530727Y0959348
X0536279Y0956159
X0528877Y0949781
X0534428Y0946592
X0530727Y0946592
X0536279Y0943403
X0528877Y0943403
X0534428Y0940214
X0530727Y0940214
X0536279Y0937025
X0530727Y0889191
X0528877Y0930647
X0534428Y0927458
X0530727Y0927458
X0536279Y0924269
X0528877Y0924269
X0534428Y0921080
X0530727Y0921080
X0536279Y0917891
X0528877Y0911513
X0534428Y0908325
X0536279Y0886002
X0530727Y0991238
X0536279Y0988049
X0528877Y0981671
X0534428Y0978482
X0530727Y0978482
X0536279Y0975293
X0528877Y0968915
X0534428Y0965726
X0530727Y0965726
X0536279Y0962537
X0530727Y1003994
X0534428Y1003994
X0536279Y1000805
X0528877Y1000805
X0530727Y0997616
X0534428Y0997616
X0536279Y0994427
X0528877Y0988049
X0536279Y1007183
X0534428Y1010372
X0530727Y0984860
X1511751Y1053567
X1506200Y1044000
X1511751Y1066323
X1508050Y1149236
X1508050Y1130102
X1508050Y1110969
R02Y-0019134
X1511751Y1142858
X1511751Y1123725
X1511751Y1104591
X1511751Y1085457
X1513602Y1069512
X1506200Y1146047
X1506200Y1126914
X1506200Y1107780
R02Y-0019134
X1513602Y1146047
X1513602Y1126914
X1513602Y1107780
X1513602Y1088646
X1506200Y1101402
X1511751Y1098213
X1508050Y1098213
X1513602Y1095024
X1506200Y1095024
X1511751Y1091835
X1508050Y1085457
X1508050Y1155614
X1513602Y1152425
X1513602Y1082268
X1506200Y1152425
X1511751Y1149236
X1508050Y1142858
X1513602Y1139669
X1506200Y1139669
X1511751Y1136480
X1508050Y1136480
X1513602Y1133292
X1506200Y1133292
X1511751Y1130102
X1506200Y1082268
X1508050Y1123725
X1513602Y1120536
X1506200Y1120536
X1511751Y1117347
X1508050Y1117347
X1513602Y1114158
X1506200Y1114158
X1511751Y1110969
X1508050Y1104591
X1513602Y1101402
X1511751Y1079079
X1513602Y1050378
X1508050Y1047189
X1508050Y1066323
X1513602Y1063134
X1506200Y1063134
X1511751Y1059945
X1508050Y1079079
X1513602Y1075890
X1506200Y1075890
X1511751Y1072701
X1511751Y1040811
X1508050Y1040811
X1506200Y1037622
X1513602Y1037622
X1511751Y1034433
X1508050Y1034433
X1506200Y1031244
X1506200Y1050378
X1505019Y1007182
X1505019Y0975292
X1505019Y0956158
R02Y-0019134
X1505019Y0898757
X1512421Y0968914
R03Y-0019134
X1512421Y0892379
X1506869Y0972103
R03Y-0019134
X1506869Y0895568
X1510570Y0972103
R03Y-0019134
X1510570Y0895568
X1506869Y0908324
X1512421Y0905134
X1505019Y0905134
X1510570Y0901946
X1506869Y0901946
X1512421Y0898757
X1505019Y0892379
X1505019Y0962536
X1510570Y0959347
X1510570Y0889190
X1506869Y0959347
X1512421Y0956158
X1505019Y0949780
X1510570Y0946591
X1506869Y0946591
X1512421Y0943402
X1505019Y0943402
X1510570Y0940213
X1506869Y0940213
X1512421Y0937024
X1506869Y0889190
X1505019Y0930646
X1510570Y0927457
X1506869Y0927457
X1512421Y0924268
X1505019Y0924268
X1510570Y0921079
X1506869Y0921079
X1512421Y0917890
X1505019Y0911512
X1510570Y0908324
X1512421Y0886001
X1506869Y0991237
X1512421Y0988048
X1505019Y0981670
X1510570Y0978481
X1506869Y0978481
X1512421Y0975292
X1505019Y0968914
X1510570Y0965725
X1506869Y0965725
X1512421Y0962536
X1506869Y1003993
X1510570Y1003993
X1512421Y1000804
X1505019Y1000804
X1506869Y0997615
X1510570Y0997615
X1512421Y0994426
X1505019Y0988048
X1512421Y1007182
X1510570Y1010371
X1506869Y0984859
X0346894Y1053568
X0345043Y1044001
X0346894Y1066324
X0350595Y1149237
X0350595Y1130103
X0350595Y1110970
R02Y-0019134
X0346894Y1142859
X0346894Y1123726
X0346894Y1104592
X0346894Y1085458
X0345043Y1069513
X0352445Y1146048
X0352445Y1126915
X0352445Y1107781
R02Y-0019134
X0345043Y1146048
X0345043Y1126915
X0345043Y1107781
X0345043Y1088647
X0352445Y1101403
X0346894Y1098214
X0350595Y1098214
X0345043Y1095025
X0352445Y1095025
X0346894Y1091836
X0350595Y1085458
X0350595Y1155615
X0345043Y1152426
X0345043Y1082269
X0352445Y1152426
X0346894Y1149237
X0350595Y1142859
X0345043Y1139670
X0352445Y1139670
X0346894Y1136481
X0350595Y1136481
X0345043Y1133293
X0352445Y1133293
X0346894Y1130103
X0352445Y1082269
X0350595Y1123726
X0345043Y1120537
X0352445Y1120537
X0346894Y1117348
X0350595Y1117348
X0345043Y1114159
X0352445Y1114159
X0346894Y1110970
X0350595Y1104592
X0345043Y1101403
X0346894Y1079080
X0345043Y1050379
X0350595Y1047190
X0350595Y1066324
X0345043Y1063135
X0352445Y1063135
X0346894Y1059946
X0350595Y1079080
X0345043Y1075891
X0352445Y1075891
X0346894Y1072702
X0346894Y1040812
X0350595Y1040812
X0352445Y1037623
X0345043Y1037623
X0346894Y1034434
X0350595Y1034434
X0352445Y1031245
X0352445Y1050379
X0351264Y1007183
X0351264Y0975293
X0351264Y0956159
R02Y-0019134
X0351264Y0898758
X0343862Y0968915
R03Y-0019134
X0343862Y0892380
X0349414Y0972104
R03Y-0019134
X0349414Y0895569
X0345713Y0972104
R03Y-0019134
X0345713Y0895569
X0349414Y0908325
X0343862Y0905135
X0351264Y0905135
X0345713Y0901947
X0349414Y0901947
X0343862Y0898758
X0351264Y0892380
X0351264Y0962537
X0345713Y0959348
X0345713Y0889191
X0349414Y0959348
X0343862Y0956159
X0351264Y0949781
X0345713Y0946592
X0349414Y0946592
X0343862Y0943403
X0351264Y0943403
X0345713Y0940214
X0349414Y0940214
X0343862Y0937025
X0349414Y0889191
X0351264Y0930647
X0345713Y0927458
X0349414Y0927458
X0343862Y0924269
X0351264Y0924269
X0345713Y0921080
X0349414Y0921080
X0343862Y0917891
X0351264Y0911513
X0345713Y0908325
X0343862Y0886002
X0351264Y0994427
X0345713Y0991238
X0351264Y0981671
X0345713Y0978482
X0349414Y0978482
X0343862Y0975293
X0351264Y0968915
X0345713Y0965726
X0349414Y0965726
X0343862Y0962537
X0349414Y1003994
X0345713Y1003994
X0343862Y1000805
X0351264Y1000805
X0349414Y0997616
X0345713Y0997616
X0343862Y0994427
X0351264Y0988049
X0343862Y1007183
X0345713Y1010372
X0349414Y0984860
X1323036Y1053567
X1321185Y1044000
X1323036Y1066323
X1326737Y1149236
X1326737Y1130102
X1326737Y1110969
R02Y-0019134
X1323036Y1142858
X1323036Y1123725
X1323036Y1104591
X1323036Y1085457
X1321185Y1069512
X1328587Y1146047
X1328587Y1126914
X1328587Y1107780
R02Y-0019134
X1321185Y1146047
X1321185Y1126914
X1321185Y1107780
X1321185Y1088646
X1328587Y1101402
X1323036Y1098213
X1326737Y1098213
X1321185Y1095024
X1328587Y1095024
X1323036Y1091835
X1326737Y1085457
X1326737Y1155614
X1321185Y1152425
X1321185Y1082268
X1328587Y1152425
X1323036Y1149236
X1326737Y1142858
X1321185Y1139669
X1328587Y1139669
X1323036Y1136480
X1326737Y1136480
X1321185Y1133292
X1328587Y1133292
X1323036Y1130102
X1328587Y1082268
X1326737Y1123725
X1321185Y1120536
X1328587Y1120536
X1323036Y1117347
X1326737Y1117347
X1321185Y1114158
X1328587Y1114158
X1323036Y1110969
X1326737Y1104591
X1321185Y1101402
X1323036Y1079079
X1321185Y1050378
X1326737Y1047189
X1326737Y1066323
X1321185Y1063134
X1328587Y1063134
X1323036Y1059945
X1326737Y1079079
X1321185Y1075890
X1328587Y1075890
X1323036Y1072701
X1323036Y1040811
X1326737Y1040811
X1328587Y1037622
X1321185Y1037622
X1323036Y1034433
X1326737Y1034433
X1328587Y1031244
X1328587Y1050378
X1327406Y1007182
X1327406Y0975292
X1327406Y0956158
R02Y-0019134
X1327406Y0898757
X1320004Y0968914
R03Y-0019134
X1320004Y0892379
X1325556Y0972103
R03Y-0019134
X1325556Y0895568
X1321855Y0972103
R03Y-0019134
X1321855Y0895568
X1325556Y0908324
X1320004Y0905134
X1327406Y0905134
X1321855Y0901946
X1325556Y0901946
X1320004Y0898757
X1327406Y0892379
X1327406Y0962536
X1321855Y0959347
X1321855Y0889190
X1325556Y0959347
X1320004Y0956158
X1327406Y0949780
X1321855Y0946591
X1325556Y0946591
X1320004Y0943402
X1327406Y0943402
X1321855Y0940213
X1325556Y0940213
X1320004Y0937024
X1325556Y0889190
X1327406Y0930646
X1321855Y0927457
X1325556Y0927457
X1320004Y0924268
X1327406Y0924268
X1321855Y0921079
X1325556Y0921079
X1320004Y0917890
X1327406Y0911512
X1321855Y0908324
X1320004Y0886001
X1327406Y0994426
X1321855Y0991237
X1327406Y0981670
X1321855Y0978481
X1325556Y0978481
X1320004Y0975292
X1327406Y0968914
X1321855Y0965725
X1325556Y0965725
X1320004Y0962536
X1325556Y1003993
X1321855Y1003993
X1320004Y1000804
X1327406Y1000804
X1325556Y0997615
X1321855Y0997615
X1320004Y0994426
X1327406Y0988048
X1320004Y1007182
X1321855Y1010371
X1325556Y0984859
X0469664Y0949781
X1386619Y0949780
X0469664Y0943403
X1386619Y0943402
X0469664Y0956159
X1386619Y0956158
X0458562Y0949781
X1397721Y0949780
X0458562Y0943403
X1397721Y0943402
X0458562Y0937025
X1397721Y0937024
X0458562Y0956159
X1397721Y0956158
X0449310Y0940214
X1406973Y0940213
X0449310Y0946592
X1406973Y0946591
X0491869Y0949781
X1364414Y0949780
X0491869Y0943403
X1364414Y0943402
X0491869Y0956159
X1364414Y0956158
X0480767Y0949781
X1375516Y0949780
X0480767Y0943403
X1375516Y0943402
X0480767Y0956159
X1375516Y0956158
X0449310Y0952970
X1406973Y0952969
X0473365Y0949781
X1382918Y0949780
X0473365Y0943403
X1382918Y0943402
X0473365Y0956159
X1382918Y0956158
X0462263Y0949781
X1394020Y0949780
X0462263Y0943403
X1394020Y0943402
X0462263Y0937025
X1394020Y0937024
X0462263Y0956159
X1394020Y0956158
X0453011Y0940214
X1403272Y0940213
X0453011Y0946592
X1403272Y0946591
X0495570Y0949781
X1360713Y0949780
X0495570Y0943403
X1360713Y0943402
X0495570Y0956159
X1360713Y0956158
X0484467Y0949781
X1371815Y0949780
X0484467Y0943403
X1371815Y0943402
X0484467Y0956159
X1371815Y0956158
X0453011Y0952970
X1403272Y0952969
M00
X0494947Y1548397
X0490223Y1548397
X0485498Y1548397
X0480774Y1548397
X0476049Y1548397
X0471325Y1548397
X0466600Y1548397
X0461876Y1548397
X0457151Y1548397
X0523293Y1548397
X0518569Y1548397
X0513844Y1548397
X0509120Y1548397
R02X-0004724
X0452427Y1548397
X0494947Y1544997
X0490223Y1544997
X0485498Y1544997
X0480774Y1544997
X0476049Y1544997
X0471325Y1544997
X0466600Y1544997
X0461876Y1544997
X0457151Y1544997
X0523293Y1544997
X0518569Y1544997
X0513844Y1544997
X0509120Y1544997
R02X-0004724
X0452427Y1544997
X0358836Y1548397
X0354112Y1548397
X0349387Y1548397
X0344663Y1548397
X0339938Y1548397
X0335214Y1548397
X0330489Y1548397
X0325765Y1548397
X0321040Y1548397
X0387182Y1548397
X0382458Y1548397
X0377733Y1548397
X0373009Y1548397
R02X-0004724
X0316316Y1548397
X0358836Y1544997
X0354112Y1544997
X0349387Y1544997
X0344663Y1544997
X0339938Y1544997
X0335214Y1544997
X0330489Y1544997
X0325765Y1544997
X0321040Y1544997
X0387182Y1544997
X0382458Y1544997
X0377733Y1544997
X0373009Y1544997
R02X-0004724
X0316316Y1544997
X1502821Y1581397
X1498097Y1581397
X1493372Y1581397
X1488648Y1581397
X1483923Y1581397
X1479199Y1581397
X1474474Y1581397
X1469750Y1581397
X1465025Y1581397
X1531167Y1581397
X1526443Y1581397
X1521718Y1581397
X1516994Y1581397
R02X-0004724
X1460301Y1581397
X1502821Y1577997
X1498097Y1577997
X1493372Y1577997
X1488648Y1577997
X1483923Y1577997
X1479199Y1577997
X1474474Y1577997
X1469750Y1577997
X1465025Y1577997
X1531167Y1577997
X1526443Y1577997
X1521718Y1577997
X1516994Y1577997
R02X-0004724
X1460301Y1577997
X1366709Y1581397
X1361985Y1581397
X1357260Y1581397
X1352536Y1581397
X1347811Y1581397
X1343087Y1581397
X1338362Y1581397
X1333638Y1581397
X1328913Y1581397
X1395055Y1581397
X1390331Y1581397
X1385606Y1581397
X1380882Y1581397
R02X-0004724
X1324189Y1581397
X1366709Y1577997
X1361985Y1577997
X1357260Y1577997
X1352536Y1577997
X1347811Y1577997
X1343087Y1577997
X1338362Y1577997
X1333638Y1577997
X1328913Y1577997
X1395055Y1577997
X1390331Y1577997
X1385606Y1577997
X1380882Y1577997
R02X-0004724
X1324189Y1577997
X0621886Y1452895
X0615186Y1462595
X0608486Y1472295
X0595086Y1452895
X0588386Y1462595
X0581686Y1472295
X0568286Y1452895
X0561586Y1462595
X0555348Y1480190
X0672856Y1494082
X0672856Y1480682
X0662086Y1452895
X0648686Y1452895
X0641986Y1462595
X0635286Y1472295
X0555348Y1505390
X0625286Y1452895
X0618586Y1462595
X0611886Y1472295
X0598486Y1452895
X0591786Y1462595
X0585086Y1472295
X0571686Y1452895
X0564986Y1462595
X0555348Y1483590
X0672856Y1497482
X0672856Y1484082
X0665486Y1452895
X0652086Y1452895
X0645386Y1462595
X0638686Y1472295
X0555348Y1501990
X1629760Y1485895
X1623060Y1495595
X1616360Y1505295
X1602960Y1485895
X1596260Y1495595
X1589560Y1505295
X1576160Y1485895
X1569460Y1495595
X1563222Y1513190
X1680730Y1527082
X1680730Y1513682
X1669960Y1485895
X1656560Y1485895
X1649860Y1495595
X1643160Y1505295
X1563222Y1538390
X1633160Y1485895
X1626460Y1495595
X1619760Y1505295
X1606360Y1485895
X1599660Y1495595
X1592960Y1505295
X1579560Y1485895
X1572860Y1495595
X1563222Y1516590
X1680730Y1530482
X1680730Y1517082
X1673360Y1485895
X1659960Y1485895
X1653260Y1495595
X1646560Y1505295
X1563222Y1534990
X0693197Y1064706
X0677055Y1051320
X0693197Y1084785
X0677055Y1238722
R04Y-0036811
X0693197Y1232029
R03Y-0036811
X0693197Y1088131
X0677055Y1235375
R04Y-0036811
X0693197Y1235375
R03Y-0036811
X0693197Y1151714
X0693197Y1145021
X0677055Y1141675
X0677055Y1134982
X0693197Y1138328
X0693197Y1131635
X0677055Y1118249
X0677055Y1252108
X0677055Y1245415
X0677055Y1111556
X0693197Y1248761
X0693197Y1242068
X0677055Y1228682
X0677055Y1221989
X0693197Y1225336
X0693197Y1218643
X0677055Y1215297
X0677055Y1208604
X0693197Y1211950
X0693197Y1205257
X0693197Y1114903
X0677055Y1191871
X0677055Y1185178
X0693197Y1188525
X0693197Y1181832
X0677055Y1178486
X0677055Y1171793
X0693197Y1175139
X0693197Y1168446
X0677055Y1155060
X0677055Y1148367
X0693197Y1108210
X0677055Y1058013
X0693197Y1054667
X0677055Y1081438
X0677055Y1074745
X0693197Y1078092
X0693197Y1071399
X0677055Y1104863
X0677055Y1098171
X0693197Y1101517
X0693197Y1094824
X0693197Y1047974
X0677055Y1044627
X0693197Y1041281
X0677055Y1037934
X0693197Y1034588
X0677055Y1031241
X0693197Y1027895
X0693197Y1061360
X0693197Y1001123
X0677055Y0944234
X0677055Y0907423
X0677055Y0870611
R02Y-0036811
X0693197Y0937541
R04Y-0036811
X0677055Y0940887
R04Y-0036811
X0693197Y0940887
R04Y-0036811
X0693197Y0820415
X0693197Y0813722
X0677055Y0810375
X0677055Y0803682
X0693197Y0807029
X0693197Y0800336
X0677055Y0786950
X0677055Y0920808
X0677055Y0914115
X0677055Y0780257
X0693197Y0917462
X0693197Y0910769
X0677055Y0897383
X0677055Y0890690
X0693197Y0894037
X0693197Y0887344
X0677055Y0883997
X0677055Y0877304
X0693197Y0880651
X0693197Y0873958
X0693197Y0783604
X0677055Y0860572
X0677055Y0853879
X0693197Y0857226
X0693197Y0850533
X0677055Y0847186
X0677055Y0840493
X0693197Y0843840
X0693197Y0837147
X0677055Y0823761
X0677055Y0817068
X0693197Y0776911
X0677055Y0971005
X0693197Y0967659
X0677055Y0957619
X0677055Y0950926
X0693197Y0954273
X0693197Y0947580
X0677055Y0934194
X0677055Y0927501
X0693197Y0930848
X0693197Y0924155
X0693197Y0994430
X0677055Y0991084
X0693197Y0987737
X0677055Y0984391
X0693197Y0981045
X0677055Y0977698
X0693197Y0974352
X0677055Y0964312
X0677055Y0997777
X0677055Y1001123
X1669339Y1064705
X1653197Y1051319
X1669339Y1084784
X1653197Y1238721
R04Y-0036811
X1669339Y1232028
R03Y-0036811
X1669339Y1088130
X1653197Y1235374
R04Y-0036811
X1669339Y1235374
R03Y-0036811
X1669339Y1151713
X1669339Y1145020
X1653197Y1141674
X1653197Y1134981
X1669339Y1138327
X1669339Y1131634
X1653197Y1118248
X1653197Y1252107
X1653197Y1245414
X1653197Y1111555
X1669339Y1248760
X1669339Y1242067
X1653197Y1228681
X1653197Y1221988
X1669339Y1225335
X1669339Y1218642
X1653197Y1215296
X1653197Y1208603
X1669339Y1211949
X1669339Y1205256
X1669339Y1114902
X1653197Y1191870
X1653197Y1185177
X1669339Y1188524
X1669339Y1181831
X1653197Y1178485
X1653197Y1171792
X1669339Y1175138
X1669339Y1168445
X1653197Y1155059
X1653197Y1148366
X1669339Y1108209
X1653197Y1058012
X1669339Y1054666
X1653197Y1081437
X1653197Y1074744
X1669339Y1078091
X1669339Y1071398
X1653197Y1104862
X1653197Y1098170
X1669339Y1101516
X1669339Y1094823
X1669339Y1047973
X1653197Y1044626
X1669339Y1041280
X1653197Y1037933
X1669339Y1034587
X1653197Y1031240
X1669339Y1027894
X1669339Y1061359
X1669339Y1001122
X1653197Y0944233
X1653197Y0907422
X1653197Y0870610
R02Y-0036811
X1669339Y0937540
R04Y-0036811
X1653197Y0940886
R04Y-0036811
X1669339Y0940886
R04Y-0036811
X1669339Y0820414
X1669339Y0813721
X1653197Y0810374
X1653197Y0803681
X1669339Y0807028
X1669339Y0800335
X1653197Y0786949
X1653197Y0920807
X1653197Y0914114
X1653197Y0780256
X1669339Y0917461
X1669339Y0910768
X1653197Y0897382
X1653197Y0890689
X1669339Y0894036
X1669339Y0887343
X1653197Y0883996
X1653197Y0877303
X1669339Y0880650
X1669339Y0873957
X1669339Y0783603
X1653197Y0860571
X1653197Y0853878
X1669339Y0857225
X1669339Y0850532
X1653197Y0847185
X1653197Y0840492
X1669339Y0843839
X1669339Y0837146
X1653197Y0823760
X1653197Y0817067
X1669339Y0776910
X1653197Y0971004
X1669339Y0967658
X1653197Y0957618
X1653197Y0950925
X1669339Y0954272
X1669339Y0947579
X1653197Y0934193
X1653197Y0927500
X1669339Y0930847
X1669339Y0924154
X1669339Y0994429
X1653197Y0991083
X1669339Y0987736
X1653197Y0984390
X1669339Y0981044
X1653197Y0977697
X1669339Y0974351
X1653197Y0964311
X1653197Y0997776
X1653197Y1001122
X0204268Y1064706
X0188126Y1051320
X0204268Y1084785
X0188126Y1238722
R04Y-0036811
X0204268Y1232029
R03Y-0036811
X0204268Y1088131
X0188126Y1235375
R04Y-0036811
X0204268Y1235375
R03Y-0036811
X0204268Y1151714
X0204268Y1145021
X0188126Y1141675
X0188126Y1134982
X0204268Y1138328
X0204268Y1131635
X0188126Y1118249
X0188126Y1252108
X0188126Y1245415
X0188126Y1111556
X0204268Y1248761
X0204268Y1242068
X0188126Y1228682
X0188126Y1221989
X0204268Y1225336
X0204268Y1218643
X0188126Y1215297
X0188126Y1208604
X0204268Y1211950
X0204268Y1205257
X0204268Y1114903
X0188126Y1191871
X0188126Y1185178
X0204268Y1188525
X0204268Y1181832
X0188126Y1178486
X0188126Y1171793
X0204268Y1175139
X0204268Y1168446
X0188126Y1155060
X0188126Y1148367
X0204268Y1108210
X0188126Y1058013
X0204268Y1054667
X0188126Y1081438
X0188126Y1074745
X0204268Y1078092
X0204268Y1071399
X0188126Y1104863
X0188126Y1098171
X0204268Y1101517
X0204268Y1094824
X0204268Y1047974
X0188126Y1044627
X0204268Y1041281
X0188126Y1037934
X0204268Y1034588
X0188126Y1031241
X0204268Y1027895
X0204268Y1061360
X0204268Y1001123
X0188126Y0944234
X0188126Y0907423
X0188126Y0870611
R02Y-0036811
X0204268Y0937541
R04Y-0036811
X0188126Y0940887
R04Y-0036811
X0204268Y0940887
R04Y-0036811
X0204268Y0820415
X0204268Y0813722
X0188126Y0810375
X0188126Y0803682
X0204268Y0807029
X0204268Y0800336
X0188126Y0786950
X0188126Y0920808
X0188126Y0914115
X0188126Y0780257
X0204268Y0917462
X0204268Y0910769
X0188126Y0897383
X0188126Y0890690
X0204268Y0894037
X0204268Y0887344
X0188126Y0883997
X0188126Y0877304
X0204268Y0880651
X0204268Y0873958
X0204268Y0783604
X0188126Y0860572
X0188126Y0853879
X0204268Y0857226
X0204268Y0850533
X0188126Y0847186
X0188126Y0840493
X0204268Y0843840
X0204268Y0837147
X0188126Y0823761
X0188126Y0817068
X0204268Y0776911
X0188126Y0971005
X0204268Y0967659
X0188126Y0957619
X0188126Y0950926
X0204268Y0954273
X0204268Y0947580
X0188126Y0934194
X0188126Y0927501
X0204268Y0930848
X0204268Y0924155
X0204268Y0994430
X0188126Y0991084
X0204268Y0987737
X0188126Y0984391
X0204268Y0981045
X0188126Y0977698
X0204268Y0974352
X0188126Y0964312
X0188126Y0997777
X0188126Y1001123
X1180410Y1064705
X1164268Y1051319
X1180410Y1084784
X1164268Y1238721
R04Y-0036811
X1180410Y1232028
R03Y-0036811
X1180410Y1088130
X1164268Y1235374
R04Y-0036811
X1180410Y1235374
R03Y-0036811
X1180410Y1151713
X1180410Y1145020
X1164268Y1141674
X1164268Y1134981
X1180410Y1138327
X1180410Y1131634
X1164268Y1118248
X1164268Y1252107
X1164268Y1245414
X1164268Y1111555
X1180410Y1248760
X1180410Y1242067
X1164268Y1228681
X1164268Y1221988
X1180410Y1225335
X1180410Y1218642
X1164268Y1215296
X1164268Y1208603
X1180410Y1211949
X1180410Y1205256
X1180410Y1114902
X1164268Y1191870
X1164268Y1185177
X1180410Y1188524
X1180410Y1181831
X1164268Y1178485
X1164268Y1171792
X1180410Y1175138
X1180410Y1168445
X1164268Y1155059
X1164268Y1148366
X1180410Y1108209
X1164268Y1058012
X1180410Y1054666
X1164268Y1081437
X1164268Y1074744
X1180410Y1078091
X1180410Y1071398
X1164268Y1104862
X1164268Y1098170
X1180410Y1101516
X1180410Y1094823
X1180410Y1047973
X1164268Y1044626
X1180410Y1041280
X1164268Y1037933
X1180410Y1034587
X1164268Y1031240
X1180410Y1027894
X1180410Y1061359
X1180410Y1001122
X1164268Y0944233
X1164268Y0907422
X1164268Y0870610
R02Y-0036811
X1180410Y0937540
R04Y-0036811
X1164268Y0940886
R04Y-0036811
X1180410Y0940886
R04Y-0036811
X1180410Y0820414
X1180410Y0813721
X1164268Y0810374
X1164268Y0803681
X1180410Y0807028
X1180410Y0800335
X1164268Y0786949
X1164268Y0920807
X1164268Y0914114
X1164268Y0780256
X1180410Y0917461
X1180410Y0910768
X1164268Y0897382
X1164268Y0890689
X1180410Y0894036
X1180410Y0887343
X1164268Y0883996
X1164268Y0877303
X1180410Y0880650
X1180410Y0873957
X1180410Y0783603
X1164268Y0860571
X1164268Y0853878
X1180410Y0857225
X1180410Y0850532
X1164268Y0847185
X1164268Y0840492
X1180410Y0843839
X1180410Y0837146
X1164268Y0823760
X1164268Y0817067
X1180410Y0776910
X1164268Y0971004
X1180410Y0967658
X1164268Y0957618
X1164268Y0950925
X1180410Y0954272
X1180410Y0947579
X1164268Y0934193
X1164268Y0927500
X1180410Y0930847
X1180410Y0924154
X1180410Y0994429
X1164268Y0991083
X1180410Y0987736
X1164268Y0984390
X1180410Y0981044
X1164268Y0977697
X1180410Y0974351
X1164268Y0964311
X1164268Y0997776
X1164268Y1001122
M00
X0337205Y1714527
X0352953Y1714527
X0329331Y1710590
X0337205Y1709803
X0345079Y1710590
X0352953Y1709803
X0329331Y1705866
X0345079Y1705866
X0305709Y1714527
X0321457Y1714527
X0297835Y1710590
X0305709Y1709803
X0313583Y1710590
X0321457Y1709803
X0297835Y1705866
X0313583Y1705866
X0270275Y1714527
X0286023Y1714527
X0262401Y1710590
X0270275Y1709803
X0278149Y1710590
X0286023Y1709803
X0262401Y1705866
X0278149Y1705866
X0238779Y1714527
X0254527Y1714527
X0230905Y1710590
X0238779Y1709803
X0246653Y1710590
X0254527Y1709803
X0230905Y1705866
X0246653Y1705866
X0534448Y1714527
X0550196Y1714527
X0526574Y1710590
X0534448Y1709803
X0542322Y1710590
X0550196Y1709803
X0526574Y1705866
X0542322Y1705866
X0502952Y1714527
X0518700Y1714527
X0495078Y1710590
X0502952Y1709803
X0510826Y1710590
X0518700Y1709803
X0495078Y1705866
X0510826Y1705866
X0601378Y1714527
X0617126Y1714527
X0593504Y1710590
X0601378Y1709803
X0609252Y1710590
X0617126Y1709803
X0593504Y1705866
X0609252Y1705866
X0569882Y1714527
X0585630Y1714527
X0562008Y1710590
X0569882Y1709803
X0577756Y1710590
X0585630Y1709803
X0562008Y1705866
X0577756Y1705866
X1345078Y1714527
X1360826Y1714527
X1337204Y1710590
X1345078Y1709803
X1352952Y1710590
X1360826Y1709803
X1337204Y1705866
X1352952Y1705866
X1313582Y1714527
X1329330Y1714527
X1305708Y1710590
X1313582Y1709803
X1321456Y1710590
X1329330Y1709803
X1305708Y1705866
X1321456Y1705866
X1278148Y1714527
X1293896Y1714527
X1270274Y1710590
X1278148Y1709803
X1286022Y1710590
X1293896Y1709803
X1270274Y1705866
X1286022Y1705866
X1246652Y1714527
X1262400Y1714527
X1238778Y1710590
X1246652Y1709803
X1254526Y1710590
X1262400Y1709803
X1238778Y1705866
X1254526Y1705866
X1542322Y1714527
X1558070Y1714527
X1534448Y1710590
X1542322Y1709803
X1550196Y1710590
X1558070Y1709803
X1534448Y1705866
X1550196Y1705866
X1510826Y1714527
X1526574Y1714527
X1502952Y1710590
X1510826Y1709803
X1518700Y1710590
X1526574Y1709803
X1502952Y1705866
X1518700Y1705866
X1609252Y1714527
X1625000Y1714527
X1601378Y1710590
X1609252Y1709803
X1617126Y1710590
X1625000Y1709803
X1601378Y1705866
X1617126Y1705866
X1577756Y1714527
X1593504Y1714527
X1569882Y1710590
X1577756Y1709803
X1585630Y1710590
X1593504Y1709803
X1569882Y1705866
X1585630Y1705866
M30
